# T6G (Grand Teton) — schematic netlist excerpt (pin names and nets, part order shuffled) for the footprints in the layout excerpt that follows; sources: Cadence DE-HDL packaged netlist, KiCad conversion of 04192023_DAF0TMB3IC0_F0TG_MB_C_brd_V02_OCP.brd

C982  Q_CAP  0.1UF 10V 10% X7S  pkg C0201  page 301 : A = P0V9_CPU0_RT2_2A ; B = GND
R1705  Q_RES  10 1% CHIP  pkg 0402LF  page 104 : A = I3C_SPD_DDRGL_CPU1_SDA ; B = I3C_SPD_DDRG_CPU1_SDA
C133  Q_CAP  0.1UF 10V 10% X7S  pkg C0201  page 323 : A = P1V8_CPU1_RT0_1A ; B = GND

(kicad_pcb
	(version 20260206)
	(generator "pcbnew")
	(generator_version "10.0")
	(general
		(thickness 1.6)
		(legacy_teardrops no)
	)
	(paper "A4")
	(title_block
		(title "04192023_DAF0TMB3IC0_F0TG_MB_C_brd_V02_OCP.brd")
		(comment 1 "Grand Teton / footprints 5713-5715 of 8354")
	)
	(layers
		(0 "F.Cu" signal "TOP")
		(4 "In1.Cu" signal "GND")
		(6 "In2.Cu" signal "IN1")
		(8 "In3.Cu" signal "GND1")
		(10 "In4.Cu" signal "IN2")
		(12 "In5.Cu" signal "GND2")
		(14 "In6.Cu" signal "IN3")
		(16 "In7.Cu" signal "GND3")
		(18 "In8.Cu" signal "VCC")
		(20 "In9.Cu" signal "VCC1")
		(22 "In10.Cu" signal "GND4")
		(24 "In11.Cu" signal "IN4")
		(26 "In12.Cu" signal "GND5")
		(28 "In13.Cu" signal "IN5")
		(30 "In14.Cu" signal "GND6")
		(32 "In15.Cu" signal "IN6")
		(34 "In16.Cu" signal "GND7")
		(2 "B.Cu" signal "BOTTOM")
		(9 "F.Adhes" user "F.Adhesive")
		(11 "B.Adhes" user "B.Adhesive")
		(13 "F.Paste" user "Package Geometry/Pastemask Top")
		(15 "B.Paste" user "Package Geometry/Pastemask Bottom")
		(5 "F.SilkS" user "Ref Des/Silkscreen Top")
		(7 "B.SilkS" user "Ref Des/Silkscreen Bottom")
		(1 "F.Mask" user "Board Geometry/Soldermask Top")
		(3 "B.Mask" user "Board Geometry/Soldermask Bottom")
		(17 "Dwgs.User" user "User.Drawings")
		(19 "Cmts.User" user "User.Comments")
		(21 "Eco1.User" user "User.Eco1")
		(23 "Eco2.User" user "User.Eco2")
		(25 "Edge.Cuts" user "Board Geometry/Outline")
		(27 "Margin" user)
		(31 "F.CrtYd" user "Package Geometry/Place Bound Top")
		(29 "B.CrtYd" user "Package Geometry/Place Bound Bottom")
		(35 "F.Fab" user "Ref Des/Assembly Top")
		(33 "B.Fab" user "Ref Des/Assembly Bottom")
	)
	(footprint ""
		(layer "B.Cu")
		(at 55.778654 -386.766562 90)
		(property "Reference" "C133"
			(at 0 0 90)
			(layer "B.SilkS")
			(hide yes)
			(effects
				(font
					(size 1.27 1.27)
				)
				(justify mirror)
			)
		)
		(property "Value" ""
			(at 0 0 90)
			(layer "B.Fab")
			(effects
				(font
					(size 1.27 1.27)
				)
				(justify mirror)
			)
		)
		(duplicate_pad_numbers_are_jumpers no)
		(fp_line
			(start 0.299974 -0.150114)
			(end -0.299974 -0.150114)
			(stroke
				(width 0.1)
				(type default)
			)
			(layer "B.Fab")
		)
		(fp_line
			(start -0.299974 -0.150114)
			(end -0.299974 0.150114)
			(stroke
				(width 0.1)
				(type default)
			)
			(layer "B.Fab")
		)
		(fp_line
			(start 0.299974 0.150114)
			(end 0.299974 -0.150114)
			(stroke
				(width 0.1)
				(type default)
			)
			(layer "B.Fab")
		)
		(fp_line
			(start -0.299974 0.150114)
			(end 0.299974 0.150114)
			(stroke
				(width 0.1)
				(type default)
			)
			(layer "B.Fab")
		)
		(pad "1" smd rect
			(at 0.2667 0 270)
			(size 0.3048 0.381)
			(layers "B.Cu" "B.Mask" "B.Paste")
			(net "P1V8_CPU1_RT0_1A")
		)
		(pad "2" smd rect
			(at -0.2667 0 270)
			(size 0.3048 0.381)
			(layers "B.Cu" "B.Mask" "B.Paste")
			(net "GND")
		)
	)
	(footprint ""
		(layer "B.Cu")
		(at 167.772588 -195.8594 180)
		(property "Reference" "R1705"
			(at 0 0 0)
			(layer "B.SilkS")
			(hide yes)
			(effects
				(font
					(size 1.27 1.27)
				)
				(justify mirror)
			)
		)
		(property "Value" ""
			(at 0 0 0)
			(layer "B.Fab")
			(effects
				(font
					(size 1.27 1.27)
				)
				(justify mirror)
			)
		)
		(duplicate_pad_numbers_are_jumpers no)
		(fp_line
			(start 0.7874 0.4064)
			(end 0.7874 -0.4064)
			(stroke
				(width 0.1524)
				(type default)
			)
			(layer "B.SilkS")
		)
		(fp_line
			(start 0.7874 -0.4064)
			(end -0.7874 -0.4064)
			(stroke
				(width 0.1524)
				(type default)
			)
			(layer "B.SilkS")
		)
		(fp_line
			(start -0.7874 0.4064)
			(end 0.7874 0.4064)
			(stroke
				(width 0.1524)
				(type default)
			)
			(layer "B.SilkS")
		)
		(fp_line
			(start -0.7874 -0.4064)
			(end -0.7874 0.4064)
			(stroke
				(width 0.1524)
				(type default)
			)
			(layer "B.SilkS")
		)
		(fp_line
			(start 0.67945 0.3048)
			(end 0.67945 -0.305054)
			(stroke
				(width 0.1)
				(type default)
			)
			(layer "B.Fab")
		)
		(fp_line
			(start 0.67945 -0.305054)
			(end 0.12065 -0.305054)
			(stroke
				(width 0.1)
				(type default)
			)
			(layer "B.Fab")
		)
		(fp_line
			(start 0.12065 0.3048)
			(end 0.67945 0.3048)
			(stroke
				(width 0.1)
				(type default)
			)
			(layer "B.Fab")
		)
		(fp_line
			(start 0.12065 0.2794)
			(end 0.12065 0.3048)
			(stroke
				(width 0.1)
				(type default)
			)
			(layer "B.Fab")
		)
		(fp_line
			(start 0.12065 -0.2794)
			(end -0.12065 -0.2794)
			(stroke
				(width 0.1)
				(type default)
			)
			(layer "B.Fab")
		)
		(fp_line
			(start 0.12065 -0.305054)
			(end 0.12065 -0.2794)
			(stroke
				(width 0.1)
				(type default)
			)
			(layer "B.Fab")
		)
		(fp_line
			(start -0.120396 0.3048)
			(end -0.120396 0.2794)
			(stroke
				(width 0.1)
				(type default)
			)
			(layer "B.Fab")
		)
		(fp_line
			(start -0.120396 0.2794)
			(end 0.12065 0.2794)
			(stroke
				(width 0.1)
				(type default)
			)
			(layer "B.Fab")
		)
		(fp_line
			(start -0.12065 -0.2794)
			(end -0.12065 -0.3048)
			(stroke
				(width 0.1)
				(type default)
			)
			(layer "B.Fab")
		)
		(fp_line
			(start -0.12065 -0.3048)
			(end -0.67945 -0.3048)
			(stroke
				(width 0.1)
				(type default)
			)
			(layer "B.Fab")
		)
		(fp_line
			(start -0.67945 0.3048)
			(end -0.120396 0.3048)
			(stroke
				(width 0.1)
				(type default)
			)
			(layer "B.Fab")
		)
		(fp_line
			(start -0.67945 -0.3048)
			(end -0.67945 0.3048)
			(stroke
				(width 0.1)
				(type default)
			)
			(layer "B.Fab")
		)
		(pad "1" smd circle
			(at 0.40005 0)
			(size 0 0)
			(layers "B.Cu" "B.Mask" "B.Paste")
			(net "I3C_SPD_DDRGL_CPU1_SDA")
		)
		(pad "2" smd circle
			(at -0.40005 0)
			(size 0 0)
			(layers "B.Cu" "B.Mask" "B.Paste")
			(net "I3C_SPD_DDRG_CPU1_SDA")
		)
	)
	(footprint ""
		(layer "B.Cu")
		(at 417.546282 -396.393162 -90)
		(property "Reference" "C982"
			(at 0 0 90)
			(layer "B.SilkS")
			(hide yes)
			(effects
				(font
					(size 1.27 1.27)
				)
				(justify mirror)
			)
		)
		(property "Value" ""
			(at 0 0 90)
			(layer "B.Fab")
			(effects
				(font
					(size 1.27 1.27)
				)
				(justify mirror)
			)
		)
		(duplicate_pad_numbers_are_jumpers no)
		(fp_line
			(start -0.299974 0.150114)
			(end 0.299974 0.150114)
			(stroke
				(width 0.1)
				(type default)
			)
			(layer "B.Fab")
		)
		(fp_line
			(start 0.299974 0.150114)
			(end 0.299974 -0.150114)
			(stroke
				(width 0.1)
				(type default)
			)
			(layer "B.Fab")
		)
		(fp_line
			(start -0.299974 -0.150114)
			(end -0.299974 0.150114)
			(stroke
				(width 0.1)
				(type default)
			)
			(layer "B.Fab")
		)
		(fp_line
			(start 0.299974 -0.150114)
			(end -0.299974 -0.150114)
			(stroke
				(width 0.1)
				(type default)
			)
			(layer "B.Fab")
		)
		(pad "1" smd rect
			(at 0.2667 0 90)
			(size 0.3048 0.381)
			(layers "B.Cu" "B.Mask" "B.Paste")
			(net "P0V9_CPU0_RT2_2A")
		)
		(pad "2" smd rect
			(at -0.2667 0 90)
			(size 0.3048 0.381)
			(layers "B.Cu" "B.Mask" "B.Paste")
			(net "GND")
		)
	)
)
